(kicad_pcb
	(version 20260206)
	(generator "pcbnew")
	(generator_version "10.0")
	(general
		(thickness 1.6)
		(legacy_teardrops no)
	)
	(paper "A4")
	(title_block
		(title "pdpb — Lightning_PDPB_BRD.brd")
		(comment 1 "Lightning (Wiwynn / Facebook NVMe JBOF) / footprints 930-936 of 1140")
	)
	(layers
		(0 "F.Cu" signal "TOP")
		(4 "In1.Cu" signal "L2GND")
		(6 "In2.Cu" signal "L3")
		(8 "In3.Cu" signal "L4VCC")
		(10 "In4.Cu" signal "L5VCC")
		(12 "In5.Cu" signal "L6")
		(14 "In6.Cu" signal "L7GND")
		(2 "B.Cu" signal "BOTTOM")
		(9 "F.Adhes" user "F.Adhesive")
		(11 "B.Adhes" user "B.Adhesive")
		(13 "F.Paste" user "Package Geometry/Pastemask Top")
		(15 "B.Paste" user "Package Geometry/Pastemask Bottom")
		(5 "F.SilkS" user "Ref Des/Silkscreen Top")
		(7 "B.SilkS" user "Ref Des/Silkscreen Bottom")
		(1 "F.Mask" user "Board Geometry/Soldermask Top")
		(3 "B.Mask" user "Board Geometry/Soldermask Bottom")
		(17 "Dwgs.User" user "User.Drawings")
		(19 "Cmts.User" user "User.Comments")
		(21 "Eco1.User" user "User.Eco1")
		(23 "Eco2.User" user "User.Eco2")
		(25 "Edge.Cuts" user "Board Geometry/Outline")
		(27 "Margin" user)
		(31 "F.CrtYd" user "Package Geometry/Place Bound Top")
		(29 "B.CrtYd" user "Package Geometry/Place Bound Bottom")
		(35 "F.Fab" user "Ref Des/Assembly Top")
		(33 "B.Fab" user "Ref Des/Assembly Bottom")
	)
	(footprint ""
		(layer "F.Cu")
		(at 17.653 -491.363)
		(property "Reference" "C387"
			(at 0 0 0)
			(layer "F.SilkS")
			(hide yes)
			(effects
				(font
					(size 1.27 1.27)
				)
			)
		)
		(property "Value" "SCD1U25V2KX-2-GP"
			(at 1.1811 -2.7051 0)
			(unlocked yes)
			(layer "F.Fab")
			(hide yes)
			(effects
				(font
					(size 1.016 1.016)
					(thickness 0.1524)
				)
			)
		)
		(property "Device Type" "C402H22"
			(at 1.1811 -4.2291 0)
			(unlocked yes)
			(layer "F.Fab")
			(hide yes)
			(effects
				(font
					(size 1.016 1.016)
					(thickness 0.1524)
				)
			)
		)
		(duplicate_pad_numbers_are_jumpers no)
		(fp_rect
			(start -0.4318 0.9525)
			(end 0.4318 -0.9525)
			(stroke
				(width 0)
				(type default)
			)
			(fill no)
			(layer "F.CrtYd")
		)
		(fp_rect
			(start -0.4318 0.9525)
			(end 0.4318 -0.9525)
			(stroke
				(width 0)
				(type default)
			)
			(fill no)
			(layer "F.Fab")
		)
		(pad "1" smd custom
			(at 0 -0.4445)
			(size 0.1524 0.1524)
			(layers "F.Cu" "F.Mask" "F.Paste")
			(net "P12V")
			(options
				(clearance outline)
				(anchor circle)
			)
			(primitives
				(gr_poly
					(pts
						(arc
							(start 0.3048 -0.2032)
							(mid 0.275042 -0.275042)
							(end 0.2032 -0.3048)
						)
						(arc
							(start -0.2032 -0.3048)
							(mid -0.275042 -0.275042)
							(end -0.3048 -0.2032)
						)
						(arc
							(start -0.3048 0.2032)
							(mid -0.275042 0.275042)
							(end -0.2032 0.3048)
						)
						(arc
							(start 0.2032 0.3048)
							(mid 0.275042 0.275042)
							(end 0.3048 0.2032)
						)
					)
					(width 0)
					(fill yes)
				)
			)
		)
		(pad "2" smd custom
			(at 0 0.4445)
			(size 0.1524 0.1524)
			(layers "F.Cu" "F.Mask" "F.Paste")
			(net "SW_SSD5_N")
			(options
				(clearance outline)
				(anchor circle)
			)
			(primitives
				(gr_poly
					(pts
						(arc
							(start 0.3048 -0.2032)
							(mid 0.275042 -0.275042)
							(end 0.2032 -0.3048)
						)
						(arc
							(start -0.2032 -0.3048)
							(mid -0.275042 -0.275042)
							(end -0.3048 -0.2032)
						)
						(arc
							(start -0.3048 0.2032)
							(mid -0.275042 0.275042)
							(end -0.2032 0.3048)
						)
						(arc
							(start 0.2032 0.3048)
							(mid 0.275042 0.275042)
							(end 0.3048 0.2032)
						)
					)
					(width 0)
					(fill yes)
				)
			)
		)
	)
	(footprint ""
		(layer "F.Cu")
		(at 95.504 -424.688)
		(property "Reference" "C8837"
			(at 0 0 0)
			(layer "F.SilkS")
			(hide yes)
			(effects
				(font
					(size 1.27 1.27)
				)
			)
		)
		(property "Value" "SCD1U16V2KX-3GP"
			(at 1.1811 -2.7051 0)
			(unlocked yes)
			(layer "F.Fab")
			(hide yes)
			(effects
				(font
					(size 1.016 1.016)
					(thickness 0.1524)
				)
			)
		)
		(property "Device Type" "C402H22"
			(at 1.1811 -4.2291 0)
			(unlocked yes)
			(layer "F.Fab")
			(hide yes)
			(effects
				(font
					(size 1.016 1.016)
					(thickness 0.1524)
				)
			)
		)
		(duplicate_pad_numbers_are_jumpers no)
		(fp_rect
			(start -0.4318 0.9525)
			(end 0.4318 -0.9525)
			(stroke
				(width 0)
				(type default)
			)
			(fill no)
			(layer "F.CrtYd")
		)
		(fp_rect
			(start -0.4318 0.9525)
			(end 0.4318 -0.9525)
			(stroke
				(width 0)
				(type default)
			)
			(fill no)
			(layer "F.Fab")
		)
		(pad "1" smd custom
			(at 0 -0.4445)
			(size 0.1524 0.1524)
			(layers "F.Cu" "F.Mask" "F.Paste")
			(net "VDD_IO_1")
			(options
				(clearance outline)
				(anchor circle)
			)
			(primitives
				(gr_poly
					(pts
						(arc
							(start 0.3048 -0.2032)
							(mid 0.275042 -0.275042)
							(end 0.2032 -0.3048)
						)
						(arc
							(start -0.2032 -0.3048)
							(mid -0.275042 -0.275042)
							(end -0.3048 -0.2032)
						)
						(arc
							(start -0.3048 0.2032)
							(mid -0.275042 0.275042)
							(end -0.2032 0.3048)
						)
						(arc
							(start 0.2032 0.3048)
							(mid 0.275042 0.275042)
							(end 0.3048 0.2032)
						)
					)
					(width 0)
					(fill yes)
				)
			)
		)
		(pad "2" smd custom
			(at 0 0.4445)
			(size 0.1524 0.1524)
			(layers "F.Cu" "F.Mask" "F.Paste")
			(net "GND")
			(options
				(clearance outline)
				(anchor circle)
			)
			(primitives
				(gr_poly
					(pts
						(arc
							(start 0.3048 -0.2032)
							(mid 0.275042 -0.275042)
							(end 0.2032 -0.3048)
						)
						(arc
							(start -0.2032 -0.3048)
							(mid -0.275042 -0.275042)
							(end -0.3048 -0.2032)
						)
						(arc
							(start -0.3048 0.2032)
							(mid -0.275042 0.275042)
							(end -0.2032 0.3048)
						)
						(arc
							(start 0.2032 0.3048)
							(mid 0.275042 0.275042)
							(end 0.3048 0.2032)
						)
					)
					(width 0)
					(fill yes)
				)
			)
		)
	)
	(footprint ""
		(layer "F.Cu")
		(at 102.235 -106.807 -90)
		(property "Reference" "R9585"
			(at 0 0 270)
			(layer "F.SilkS")
			(hide yes)
			(effects
				(font
					(size 1.27 1.27)
				)
			)
		)
		(property "Value" "0R5J-L1-GP"
			(at 0 -8.9535 270)
			(unlocked yes)
			(layer "F.Fab")
			(hide yes)
			(effects
				(font
					(size 1.27 1.016)
					(thickness 0.1524)
				)
			)
		)
		(property "Device Type" "R805H24"
			(at 0 -10.6299 270)
			(unlocked yes)
			(layer "F.Fab")
			(hide yes)
			(effects
				(font
					(size 1.27 1.016)
					(thickness 0.1524)
				)
			)
		)
		(duplicate_pad_numbers_are_jumpers no)
		(fp_line
			(start -0.889 1.7018)
			(end 0.889 1.7018)
			(stroke
				(width 0.1524)
				(type default)
			)
			(layer "F.SilkS")
		)
		(fp_line
			(start 0.889 1.7018)
			(end 0.889 -0.508)
			(stroke
				(width 0.1524)
				(type default)
			)
			(layer "F.SilkS")
		)
		(fp_line
			(start -0.889 0.0762)
			(end -0.889 1.7018)
			(stroke
				(width 0.1524)
				(type default)
			)
			(layer "F.SilkS")
		)
		(fp_line
			(start -0.889 -1.7018)
			(end -0.889 0.2794)
			(stroke
				(width 0.1524)
				(type default)
			)
			(layer "F.SilkS")
		)
		(fp_line
			(start 0.889 -1.7018)
			(end 0.889 -0.381)
			(stroke
				(width 0.1524)
				(type default)
			)
			(layer "F.SilkS")
		)
		(fp_line
			(start 0.889 -1.7018)
			(end -0.889 -1.7018)
			(stroke
				(width 0.1524)
				(type default)
			)
			(layer "F.SilkS")
		)
		(fp_poly
			(pts
				(xy 0.9652 -1.778) (xy 0.9652 1.778) (xy -0.9652 1.778) (xy -0.9652 -1.778)
			)
			(stroke
				(width 0)
				(type default)
			)
			(fill no)
			(layer "F.CrtYd")
		)
		(fp_rect
			(start -0.9652 1.778)
			(end 0.9652 -1.778)
			(stroke
				(width 0)
				(type default)
			)
			(fill no)
			(layer "F.Fab")
		)
		(pad "1" smd rect
			(at 0 -0.9652 270)
			(size 1.397 1.143)
			(layers "F.Cu" "F.Mask" "F.Paste")
			(net "P3V3")
		)
		(pad "2" smd rect
			(at 0 0.9652 270)
			(size 1.397 1.143)
			(layers "F.Cu" "F.Mask" "F.Paste")
			(net "VDD_IO_4")
		)
	)
	(footprint ""
		(layer "F.Cu")
		(at 106.045 -208.026 180)
		(property "Reference" "C9363"
			(at 0 0 180)
			(layer "F.SilkS")
			(hide yes)
			(effects
				(font
					(size 1.27 1.27)
				)
			)
		)
		(property "Value" "SC1KP50V2KX-1GP"
			(at 1.1811 -2.7051 180)
			(unlocked yes)
			(layer "F.Fab")
			(hide yes)
			(effects
				(font
					(size 1.016 1.016)
					(thickness 0.1524)
				)
			)
		)
		(property "Device Type" "C402H22"
			(at 1.1811 -4.2291 180)
			(unlocked yes)
			(layer "F.Fab")
			(hide yes)
			(effects
				(font
					(size 1.016 1.016)
					(thickness 0.1524)
				)
			)
		)
		(duplicate_pad_numbers_are_jumpers no)
		(fp_rect
			(start -0.4318 0.9525)
			(end 0.4318 -0.9525)
			(stroke
				(width 0)
				(type default)
			)
			(fill no)
			(layer "F.CrtYd")
		)
		(fp_rect
			(start -0.4318 0.9525)
			(end 0.4318 -0.9525)
			(stroke
				(width 0)
				(type default)
			)
			(fill no)
			(layer "F.Fab")
		)
		(pad "1" smd custom
			(at 0 -0.4445 180)
			(size 0.1524 0.1524)
			(layers "F.Cu" "F.Mask" "F.Paste")
			(net "SSD3_CLK0_OE_R_N")
			(options
				(clearance outline)
				(anchor circle)
			)
			(primitives
				(gr_poly
					(pts
						(arc
							(start 0.3048 -0.2032)
							(mid 0.275042 -0.275042)
							(end 0.2032 -0.3048)
						)
						(arc
							(start -0.2032 -0.3048)
							(mid -0.275042 -0.275042)
							(end -0.3048 -0.2032)
						)
						(arc
							(start -0.3048 0.2032)
							(mid -0.275042 0.275042)
							(end -0.2032 0.3048)
						)
						(arc
							(start 0.2032 0.3048)
							(mid 0.275042 0.275042)
							(end 0.3048 0.2032)
						)
					)
					(width 0)
					(fill yes)
				)
			)
		)
		(pad "2" smd custom
			(at 0 0.4445 180)
			(size 0.1524 0.1524)
			(layers "F.Cu" "F.Mask" "F.Paste")
			(net "GND")
			(options
				(clearance outline)
				(anchor circle)
			)
			(primitives
				(gr_poly
					(pts
						(arc
							(start 0.3048 -0.2032)
							(mid 0.275042 -0.275042)
							(end 0.2032 -0.3048)
						)
						(arc
							(start -0.2032 -0.3048)
							(mid -0.275042 -0.275042)
							(end -0.3048 -0.2032)
						)
						(arc
							(start -0.3048 0.2032)
							(mid -0.275042 0.275042)
							(end -0.2032 0.3048)
						)
						(arc
							(start 0.2032 0.3048)
							(mid 0.275042 0.275042)
							(end 0.3048 0.2032)
						)
					)
					(width 0)
					(fill yes)
				)
			)
		)
	)
	(footprint ""
		(layer "F.Cu")
		(at 21.144992 -267.877544 180)
		(property "Reference" "C9530"
			(at 0 0 180)
			(layer "F.SilkS")
			(hide yes)
			(effects
				(font
					(size 1.27 1.27)
				)
			)
		)
		(property "Value" "SCD1U16V2KX-3GP"
			(at 1.1811 -2.7051 180)
			(unlocked yes)
			(layer "F.Fab")
			(hide yes)
			(effects
				(font
					(size 1.016 1.016)
					(thickness 0.1524)
				)
			)
		)
		(property "Device Type" "C402H22"
			(at 1.1811 -4.2291 180)
			(unlocked yes)
			(layer "F.Fab")
			(hide yes)
			(effects
				(font
					(size 1.016 1.016)
					(thickness 0.1524)
				)
			)
		)
		(duplicate_pad_numbers_are_jumpers no)
		(fp_rect
			(start -0.4318 0.9525)
			(end 0.4318 -0.9525)
			(stroke
				(width 0)
				(type default)
			)
			(fill no)
			(layer "F.CrtYd")
		)
		(fp_rect
			(start -0.4318 0.9525)
			(end 0.4318 -0.9525)
			(stroke
				(width 0)
				(type default)
			)
			(fill no)
			(layer "F.Fab")
		)
		(pad "1" smd custom
			(at 0 -0.4445 180)
			(size 0.1524 0.1524)
			(layers "F.Cu" "F.Mask" "F.Paste")
			(net "P3V3")
			(options
				(clearance outline)
				(anchor circle)
			)
			(primitives
				(gr_poly
					(pts
						(arc
							(start 0.3048 -0.2032)
							(mid 0.275042 -0.275042)
							(end 0.2032 -0.3048)
						)
						(arc
							(start -0.2032 -0.3048)
							(mid -0.275042 -0.275042)
							(end -0.3048 -0.2032)
						)
						(arc
							(start -0.3048 0.2032)
							(mid -0.275042 0.275042)
							(end -0.2032 0.3048)
						)
						(arc
							(start 0.2032 0.3048)
							(mid 0.275042 0.275042)
							(end 0.3048 0.2032)
						)
					)
					(width 0)
					(fill yes)
				)
			)
		)
		(pad "2" smd custom
			(at 0 0.4445 180)
			(size 0.1524 0.1524)
			(layers "F.Cu" "F.Mask" "F.Paste")
			(net "GND")
			(options
				(clearance outline)
				(anchor circle)
			)
			(primitives
				(gr_poly
					(pts
						(arc
							(start 0.3048 -0.2032)
							(mid 0.275042 -0.275042)
							(end 0.2032 -0.3048)
						)
						(arc
							(start -0.2032 -0.3048)
							(mid -0.275042 -0.275042)
							(end -0.3048 -0.2032)
						)
						(arc
							(start -0.3048 0.2032)
							(mid -0.275042 0.275042)
							(end -0.2032 0.3048)
						)
						(arc
							(start 0.2032 0.3048)
							(mid 0.275042 0.275042)
							(end 0.3048 0.2032)
						)
					)
					(width 0)
					(fill yes)
				)
			)
		)
	)
	(footprint ""
		(layer "F.Cu")
		(at 27.0256 -311.7596)
		(property "Reference" "PC1220"
			(at 0 0 0)
			(layer "F.SilkS")
			(hide yes)
			(effects
				(font
					(size 1.27 1.27)
				)
			)
		)
		(property "Value" "SC22U25V6KX-GP-U"
			(at -2.860802 -5.279644 0)
			(unlocked yes)
			(layer "F.Fab")
			(hide yes)
			(effects
				(font
					(size 1.016 1.016)
					(thickness 0.1524)
				)
			)
		)
		(property "Device Type" "C1206-TO0D3H75"
			(at -2.860802 -6.803644 0)
			(unlocked yes)
			(layer "F.Fab")
			(hide yes)
			(effects
				(font
					(size 1.016 1.016)
					(thickness 0.1524)
				)
			)
		)
		(duplicate_pad_numbers_are_jumpers no)
		(fp_line
			(start -1.3081 -2.3749)
			(end 1.3081 -2.3749)
			(stroke
				(width 0.1524)
				(type default)
			)
			(layer "F.SilkS")
		)
		(fp_line
			(start -1.3081 2.3749)
			(end -1.3081 -2.3749)
			(stroke
				(width 0.1524)
				(type default)
			)
			(layer "F.SilkS")
		)
		(fp_line
			(start 1.3081 -2.3749)
			(end 1.3081 2.3749)
			(stroke
				(width 0.1524)
				(type default)
			)
			(layer "F.SilkS")
		)
		(fp_line
			(start 1.3081 2.3749)
			(end -1.3081 2.3749)
			(stroke
				(width 0.1524)
				(type default)
			)
			(layer "F.SilkS")
		)
		(fp_rect
			(start -0.8001 1.6002)
			(end 0.8001 -1.6002)
			(stroke
				(width 0)
				(type default)
			)
			(fill no)
			(layer "F.CrtYd")
		)
		(fp_poly
			(pts
				(xy -1.5621 2.4511) (xy -1.5621 1.6002) (xy 0.8001 1.6002) (xy 0.8001 -1.6002) (xy -0.8001 -1.6002)
				(xy -0.8001 1.5875) (xy -1.5621 1.5875) (xy -1.5621 -2.4511) (xy 1.5621 -2.4511) (xy 1.5621 2.4511)
			)
			(stroke
				(width 0)
				(type default)
			)
			(fill no)
			(layer "F.CrtYd")
		)
		(fp_rect
			(start -1.5621 2.4511)
			(end 1.5621 -2.4511)
			(stroke
				(width 0)
				(type default)
			)
			(fill no)
			(layer "F.Fab")
		)
		(pad "1" smd rect
			(at 0 -1.392936)
			(size 2.1082 1.4478)
			(layers "F.Cu" "F.Mask" "F.Paste")
			(net "P12V_SSD11")
		)
		(pad "2" smd rect
			(at 0 1.392936)
			(size 2.1082 1.4478)
			(layers "F.Cu" "F.Mask" "F.Paste")
			(net "GND")
		)
	)
	(footprint ""
		(layer "F.Cu")
		(at 24.3078 -91.186 180)
		(property "Reference" "Q17"
			(at 0 0 180)
			(layer "F.SilkS")
			(hide yes)
			(effects
				(font
					(size 1.27 1.27)
				)
			)
		)
		(property "Value" "2N7002A-7-GP"
			(at 0.127 -8.9662 180)
			(unlocked yes)
			(layer "F.Fab")
			(hide yes)
			(effects
				(font
					(size 1.016 1.016)
					(thickness 0.1524)
				)
			)
		)
		(property "Device Type" "SOT23DGS2D4H48"
			(at 0.127 -10.4902 180)
			(unlocked yes)
			(layer "F.Fab")
			(hide yes)
			(effects
				(font
					(size 1.016 1.016)
					(thickness 0.1524)
				)
			)
		)
		(duplicate_pad_numbers_are_jumpers no)
		(fp_line
			(start 1.651 1.778)
			(end 1.651 -1.778)
			(stroke
				(width 0.1524)
				(type default)
			)
			(layer "F.SilkS")
		)
		(fp_line
			(start 1.651 -1.778)
			(end -1.651 -1.778)
			(stroke
				(width 0.1524)
				(type default)
			)
			(layer "F.SilkS")
		)
		(fp_line
			(start -1.651 1.778)
			(end 1.651 1.778)
			(stroke
				(width 0.1524)
				(type default)
			)
			(layer "F.SilkS")
		)
		(fp_line
			(start -1.651 -1.778)
			(end -1.651 1.778)
			(stroke
				(width 0.1524)
				(type default)
			)
			(layer "F.SilkS")
		)
		(fp_poly
			(pts
				(xy -1.778 1.8796) (xy -1.778 -1.8796) (xy 1.778 -1.8796) (xy 1.778 1.8796)
			)
			(stroke
				(width 0)
				(type default)
			)
			(fill no)
			(layer "F.CrtYd")
		)
		(fp_poly
			(pts
				(xy -1.778 1.8796) (xy -1.778 -1.8796) (xy 1.778 -1.8796) (xy 1.778 1.8796)
			)
			(stroke
				(width 0)
				(type default)
			)
			(fill no)
			(layer "F.Fab")
		)
		(pad "D" smd custom
			(at 0 -0.9525 180)
			(size 0.1905 0.1905)
			(layers "F.Cu" "F.Mask" "F.Paste")
			(net "SW_SSD9_R")
			(options
				(clearance outline)
				(anchor circle)
			)
			(primitives
				(gr_poly
					(pts
						(arc
							(start -0.1778 0.5715)
							(mid -0.321484 0.511984)
							(end -0.381 0.3683)
						)
						(arc
							(start -0.381 -0.3683)
							(mid -0.321484 -0.511984)
							(end -0.1778 -0.5715)
						)
						(arc
							(start 0.1778 -0.5715)
							(mid 0.321484 -0.511984)
							(end 0.381 -0.3683)
						)
						(arc
							(start 0.381 0.3683)
							(mid 0.321484 0.511984)
							(end 0.1778 0.5715)
						)
					)
					(width 0)
					(fill yes)
				)
			)
		)
		(pad "G" smd custom
			(at -0.98425 0.9525 180)
			(size 0.1905 0.1905)
			(layers "F.Cu" "F.Mask" "F.Paste")
			(net "SSD9_PWREN")
			(options
				(clearance outline)
				(anchor circle)
			)
			(primitives
				(gr_poly
					(pts
						(arc
							(start -0.1778 0.5715)
							(mid -0.321484 0.511984)
							(end -0.381 0.3683)
						)
						(arc
							(start -0.381 -0.3683)
							(mid -0.321484 -0.511984)
							(end -0.1778 -0.5715)
						)
						(arc
							(start 0.1778 -0.5715)
							(mid 0.321484 -0.511984)
							(end 0.381 -0.3683)
						)
						(arc
							(start 0.381 0.3683)
							(mid 0.321484 0.511984)
							(end 0.1778 0.5715)
						)
					)
					(width 0)
					(fill yes)
				)
			)
		)
		(pad "S" smd custom
			(at 0.98425 0.9525 180)
			(size 0.1905 0.1905)
			(layers "F.Cu" "F.Mask" "F.Paste")
			(net "GND")
			(options
				(clearance outline)
				(anchor circle)
			)
			(primitives
				(gr_poly
					(pts
						(arc
							(start -0.1778 0.5715)
							(mid -0.321484 0.511984)
							(end -0.381 0.3683)
						)
						(arc
							(start -0.381 -0.3683)
							(mid -0.321484 -0.511984)
							(end -0.1778 -0.5715)
						)
						(arc
							(start 0.1778 -0.5715)
							(mid 0.321484 -0.511984)
							(end 0.381 -0.3683)
						)
						(arc
							(start 0.381 0.3683)
							(mid 0.321484 0.511984)
							(end 0.1778 0.5715)
						)
					)
					(width 0)
					(fill yes)
				)
			)
		)
	)
)
